# S9S_MB_2U (Grand Teton) — schematic netlist excerpt (pin names and nets, part order shuffled) for the footprints in the layout excerpt that follows; sources: Cadence DE-HDL packaged netlist, KiCad conversion of 03242023_DA0F0TMBIJ0_F0T_Motherboard_J_brd_V01_OCP.brd

C302  Q_CAP  22UF 4V 20% X6S  pkg C0402  page 77 : A = PVCCIN_CPU1 ; B = GND
R3796  Q_RES  100K 1% CHIP  pkg 0402LF  page 156 : A = P3V3_AUX ; B = P3V3_OCP_FAULT_1

(kicad_pcb
	(version 20260206)
	(generator "pcbnew")
	(generator_version "10.0")
	(general
		(thickness 1.6)
		(legacy_teardrops no)
	)
	(paper "A4")
	(title_block
		(title "03242023_DA0F0TMBIJ0_F0T_Motherboard_J_brd_V01_OCP.brd")
		(comment 1 "Grand Teton / footprints 2139-2140 of 6105")
	)
	(layers
		(0 "F.Cu" signal "TOP")
		(4 "In1.Cu" signal "GND")
		(6 "In2.Cu" signal "IN1")
		(8 "In3.Cu" signal "GND1")
		(10 "In4.Cu" signal "IN2")
		(12 "In5.Cu" signal "GND2")
		(14 "In6.Cu" signal "IN3")
		(16 "In7.Cu" signal "GND3")
		(18 "In8.Cu" signal "VCC")
		(20 "In9.Cu" signal "VCC1")
		(22 "In10.Cu" signal "GND4")
		(24 "In11.Cu" signal "IN4")
		(26 "In12.Cu" signal "GND5")
		(28 "In13.Cu" signal "IN5")
		(30 "In14.Cu" signal "GND6")
		(32 "In15.Cu" signal "IN6")
		(34 "In16.Cu" signal "GND7")
		(2 "B.Cu" signal "BOTTOM")
		(9 "F.Adhes" user "F.Adhesive")
		(11 "B.Adhes" user "B.Adhesive")
		(13 "F.Paste" user "Package Geometry/Pastemask Top")
		(15 "B.Paste" user "Package Geometry/Pastemask Bottom")
		(5 "F.SilkS" user "Ref Des/Silkscreen Top")
		(7 "B.SilkS" user "Ref Des/Silkscreen Bottom")
		(1 "F.Mask" user "Board Geometry/Soldermask Top")
		(3 "B.Mask" user "Board Geometry/Soldermask Bottom")
		(17 "Dwgs.User" user "User.Drawings")
		(19 "Cmts.User" user "User.Comments")
		(21 "Eco1.User" user "User.Eco1")
		(23 "Eco2.User" user "User.Eco2")
		(25 "Edge.Cuts" user "Board Geometry/Outline")
		(27 "Margin" user)
		(31 "F.CrtYd" user "Package Geometry/Place Bound Top")
		(29 "B.CrtYd" user "Package Geometry/Place Bound Bottom")
		(35 "F.Fab" user "Ref Des/Assembly Top")
		(33 "B.Fab" user "Ref Des/Assembly Bottom")
	)
	(footprint ""
		(layer "F.Cu")
		(at 116.561616 -240.277142 90)
		(property "Reference" "C302"
			(at 0 0 90)
			(layer "F.SilkS")
			(hide yes)
			(effects
				(font
					(size 1.27 1.27)
				)
			)
		)
		(property "Value" ""
			(at 0 0 90)
			(layer "F.Fab")
			(effects
				(font
					(size 1.27 1.27)
				)
			)
		)
		(duplicate_pad_numbers_are_jumpers no)
		(fp_line
			(start 0.7874 -0.4064)
			(end 0.7874 0.4064)
			(stroke
				(width 0.1524)
				(type default)
			)
			(layer "F.SilkS")
		)
		(fp_line
			(start -0.7874 -0.4064)
			(end 0.7874 -0.4064)
			(stroke
				(width 0.1524)
				(type default)
			)
			(layer "F.SilkS")
		)
		(fp_line
			(start 0.7874 0.4064)
			(end -0.7874 0.4064)
			(stroke
				(width 0.1524)
				(type default)
			)
			(layer "F.SilkS")
		)
		(fp_line
			(start -0.7874 0.4064)
			(end -0.7874 -0.4064)
			(stroke
				(width 0.1524)
				(type default)
			)
			(layer "F.SilkS")
		)
		(fp_line
			(start -0.12065 -0.305054)
			(end -0.12065 -0.2794)
			(stroke
				(width 0.1)
				(type default)
			)
			(layer "F.Fab")
		)
		(fp_line
			(start -0.67945 -0.305054)
			(end -0.12065 -0.305054)
			(stroke
				(width 0.1)
				(type default)
			)
			(layer "F.Fab")
		)
		(fp_line
			(start 0.67945 -0.3048)
			(end 0.67945 0.3048)
			(stroke
				(width 0.1)
				(type default)
			)
			(layer "F.Fab")
		)
		(fp_line
			(start 0.12065 -0.3048)
			(end 0.67945 -0.3048)
			(stroke
				(width 0.1)
				(type default)
			)
			(layer "F.Fab")
		)
		(fp_line
			(start 0.12065 -0.2794)
			(end 0.12065 -0.3048)
			(stroke
				(width 0.1)
				(type default)
			)
			(layer "F.Fab")
		)
		(fp_line
			(start -0.12065 -0.2794)
			(end 0.12065 -0.2794)
			(stroke
				(width 0.1)
				(type default)
			)
			(layer "F.Fab")
		)
		(fp_line
			(start 0.120396 0.2794)
			(end -0.12065 0.2794)
			(stroke
				(width 0.1)
				(type default)
			)
			(layer "F.Fab")
		)
		(fp_line
			(start -0.12065 0.2794)
			(end -0.12065 0.3048)
			(stroke
				(width 0.1)
				(type default)
			)
			(layer "F.Fab")
		)
		(fp_line
			(start 0.67945 0.3048)
			(end 0.120396 0.3048)
			(stroke
				(width 0.1)
				(type default)
			)
			(layer "F.Fab")
		)
		(fp_line
			(start 0.120396 0.3048)
			(end 0.120396 0.2794)
			(stroke
				(width 0.1)
				(type default)
			)
			(layer "F.Fab")
		)
		(fp_line
			(start -0.12065 0.3048)
			(end -0.67945 0.3048)
			(stroke
				(width 0.1)
				(type default)
			)
			(layer "F.Fab")
		)
		(fp_line
			(start -0.67945 0.3048)
			(end -0.67945 -0.305054)
			(stroke
				(width 0.1)
				(type default)
			)
			(layer "F.Fab")
		)
		(pad "1" smd circle
			(at -0.40005 0 90)
			(size 0 0)
			(layers "F.Cu" "F.Mask" "F.Paste")
			(net "PVCCIN_CPU1")
		)
		(pad "2" smd circle
			(at 0.40005 0 90)
			(size 0 0)
			(layers "F.Cu" "F.Mask" "F.Paste")
			(net "GND")
		)
	)
	(footprint ""
		(layer "F.Cu")
		(at 432.151536 -101.97719)
		(property "Reference" "R3796"
			(at 0 0 0)
			(layer "F.SilkS")
			(hide yes)
			(effects
				(font
					(size 1.27 1.27)
				)
			)
		)
		(property "Value" ""
			(at 0 0 0)
			(layer "F.Fab")
			(effects
				(font
					(size 1.27 1.27)
				)
			)
		)
		(duplicate_pad_numbers_are_jumpers no)
		(fp_line
			(start -0.7874 -0.4064)
			(end 0.7874 -0.4064)
			(stroke
				(width 0.1524)
				(type default)
			)
			(layer "F.SilkS")
		)
		(fp_line
			(start -0.7874 0.4064)
			(end -0.7874 -0.4064)
			(stroke
				(width 0.1524)
				(type default)
			)
			(layer "F.SilkS")
		)
		(fp_line
			(start 0.7874 -0.4064)
			(end 0.7874 0.4064)
			(stroke
				(width 0.1524)
				(type default)
			)
			(layer "F.SilkS")
		)
		(fp_line
			(start 0.7874 0.4064)
			(end -0.7874 0.4064)
			(stroke
				(width 0.1524)
				(type default)
			)
			(layer "F.SilkS")
		)
		(fp_line
			(start -0.67945 -0.305054)
			(end -0.12065 -0.305054)
			(stroke
				(width 0.1)
				(type default)
			)
			(layer "F.Fab")
		)
		(fp_line
			(start -0.67945 0.3048)
			(end -0.67945 -0.305054)
			(stroke
				(width 0.1)
				(type default)
			)
			(layer "F.Fab")
		)
		(fp_line
			(start -0.12065 -0.305054)
			(end -0.12065 -0.2794)
			(stroke
				(width 0.1)
				(type default)
			)
			(layer "F.Fab")
		)
		(fp_line
			(start -0.12065 -0.2794)
			(end 0.12065 -0.2794)
			(stroke
				(width 0.1)
				(type default)
			)
			(layer "F.Fab")
		)
		(fp_line
			(start -0.12065 0.2794)
			(end -0.12065 0.3048)
			(stroke
				(width 0.1)
				(type default)
			)
			(layer "F.Fab")
		)
		(fp_line
			(start -0.12065 0.3048)
			(end -0.67945 0.3048)
			(stroke
				(width 0.1)
				(type default)
			)
			(layer "F.Fab")
		)
		(fp_line
			(start 0.120396 0.2794)
			(end -0.12065 0.2794)
			(stroke
				(width 0.1)
				(type default)
			)
			(layer "F.Fab")
		)
		(fp_line
			(start 0.120396 0.3048)
			(end 0.120396 0.2794)
			(stroke
				(width 0.1)
				(type default)
			)
			(layer "F.Fab")
		)
		(fp_line
			(start 0.12065 -0.3048)
			(end 0.67945 -0.3048)
			(stroke
				(width 0.1)
				(type default)
			)
			(layer "F.Fab")
		)
		(fp_line
			(start 0.12065 -0.2794)
			(end 0.12065 -0.3048)
			(stroke
				(width 0.1)
				(type default)
			)
			(layer "F.Fab")
		)
		(fp_line
			(start 0.67945 -0.3048)
			(end 0.67945 0.3048)
			(stroke
				(width 0.1)
				(type default)
			)
			(layer "F.Fab")
		)
		(fp_line
			(start 0.67945 0.3048)
			(end 0.120396 0.3048)
			(stroke
				(width 0.1)
				(type default)
			)
			(layer "F.Fab")
		)
		(pad "1" smd circle
			(at -0.40005 0)
			(size 0 0)
			(layers "F.Cu" "F.Mask" "F.Paste")
			(net "P3V3_AUX")
		)
		(pad "2" smd circle
			(at 0.40005 0)
			(size 0 0)
			(layers "F.Cu" "F.Mask" "F.Paste")
			(net "P3V3_OCP_FAULT_1")
		)
	)
)
